(kicad_pcb
	(version 20241229)
	(generator "pcbnew")
	(generator_version "9.0")
	(general
		(thickness 1.6296)
		(legacy_teardrops no)
	)
	(paper "A3")
	(title_block
		(title "Thunderbolt to 10GbE adapter")
		(date "2026-04-21")
		(rev "1.1.0")
		(company "Antmicro Ltd")
		(comment 1 "www.antmicro.com")
		(comment 9 "footprints 445-448 of 703")
	)
	(layers
		(0 "F.Cu" signal)
		(4 "In1.Cu" signal)
		(6 "In2.Cu" signal)
		(8 "In3.Cu" signal)
		(10 "In4.Cu" signal)
		(12 "In5.Cu" signal)
		(14 "In6.Cu" signal)
		(2 "B.Cu" signal)
		(9 "F.Adhes" user "F.Adhesive")
		(11 "B.Adhes" user "B.Adhesive")
		(13 "F.Paste" user)
		(15 "B.Paste" user)
		(5 "F.SilkS" user "F.Silkscreen")
		(7 "B.SilkS" user "B.Silkscreen")
		(1 "F.Mask" user)
		(3 "B.Mask" user)
		(17 "Dwgs.User" user "User.Drawings")
		(19 "Cmts.User" user "User.Comments")
		(21 "Eco1.User" user "User.Eco1")
		(23 "Eco2.User" user "User.Eco2")
		(25 "Edge.Cuts" user)
		(27 "Margin" user)
		(31 "F.CrtYd" user "F.Courtyard")
		(29 "B.CrtYd" user "B.Courtyard")
		(35 "F.Fab" user)
		(33 "B.Fab" user)
	)
	(footprint "antmicro-footprints:Tag-Connect_TC2050-IDC-NL_2x5_P1.27mm"
		(layer "B.Cu")
		(at 126.02 89 -90)
		(property "Reference" "J2"
			(at 0.2 -3.38 90)
			(layer "B.SilkS")
			(effects
				(font
					(size 0.7 0.7)
					(thickness 0.15)
				)
				(justify left bottom mirror)
			)
		)
		(property "Value" "Tag-Connect_TC2050-IDC-NL_2x5_P1.27mm"
			(at 0 -4.4 90)
			(layer "B.Fab")
			(effects
				(font
					(size 0.7 0.7)
					(thickness 0.15)
				)
				(justify left bottom mirror)
			)
		)
		(property "Datasheet" "https://www.tag-connect.com/wp-content/uploads/bsk-pdf-manager/TC2050-IDC-NL_Datasheet_8.pdf"
			(at 0 0 90)
			(layer "B.Fab")
			(hide yes)
			(effects
				(font
					(size 1.27 1.27)
					(thickness 0.15)
				)
				(justify mirror)
			)
		)
		(property "Description" "Tag Connect 2x5 1.27mm terminal"
			(at 0 0 90)
			(layer "B.Fab")
			(hide yes)
			(effects
				(font
					(size 1.27 1.27)
					(thickness 0.15)
				)
				(justify mirror)
			)
		)
		(property "MPN" "TC2050-IDC-NL"
			(at 0 0 270)
			(unlocked yes)
			(layer "B.Fab")
			(hide yes)
			(effects
				(font
					(size 1 1)
					(thickness 0.15)
				)
				(justify mirror)
			)
		)
		(property "Manufacturer" "Tag Connect"
			(at 0 0 270)
			(unlocked yes)
			(layer "B.Fab")
			(hide yes)
			(effects
				(font
					(size 1 1)
					(thickness 0.15)
				)
				(justify mirror)
			)
		)
		(property "Author" "Antmicro"
			(at 0 0 270)
			(unlocked yes)
			(layer "B.Fab")
			(hide yes)
			(effects
				(font
					(size 1 1)
					(thickness 0.15)
				)
				(justify mirror)
			)
		)
		(property "License" "Apache-2.0"
			(at 0 0 270)
			(unlocked yes)
			(layer "B.Fab")
			(hide yes)
			(effects
				(font
					(size 1 1)
					(thickness 0.15)
				)
				(justify mirror)
			)
		)
		(sheetname "/X710-AT2 PCIe/")
		(sheetfile "x710-at2-pcie.kicad_sch")
		(attr exclude_from_pos_files exclude_from_bom dnp)
		(fp_line
			(start -2.2 2.05)
			(end 4.7 2.05)
			(stroke
				(width 0.15)
				(type solid)
			)
			(layer "B.SilkS")
		)
		(fp_line
			(start 4.7 2.05)
			(end 5.1 1.7)
			(stroke
				(width 0.15)
				(type solid)
			)
			(layer "B.SilkS")
		)
		(fp_line
			(start 5.1 1.7)
			(end 5.1 -1.7)
			(stroke
				(width 0.15)
				(type solid)
			)
			(layer "B.SilkS")
		)
		(fp_line
			(start -5.08 0.9)
			(end -2.2 2.05)
			(stroke
				(width 0.15)
				(type solid)
			)
			(layer "B.SilkS")
		)
		(fp_line
			(start -5.08 -0.8)
			(end -5.08 0.9)
			(stroke
				(width 0.15)
				(type solid)
			)
			(layer "B.SilkS")
		)
		(fp_line
			(start -3.101 -1.269)
			(end -3.101 -0.4)
			(stroke
				(width 0.15)
				(type solid)
			)
			(layer "B.SilkS")
		)
		(fp_line
			(start -2.3 -2.049)
			(end -5.08 -0.8)
			(stroke
				(width 0.15)
				(type solid)
			)
			(layer "B.SilkS")
		)
		(fp_line
			(start 4.7 -2.049)
			(end 5.1 -1.7)
			(stroke
				(width 0.15)
				(type solid)
			)
			(layer "B.SilkS")
		)
		(fp_line
			(start 4.7 -2.049)
			(end -2.3 -2.049)
			(stroke
				(width 0.15)
				(type solid)
			)
			(layer "B.SilkS")
		)
		(fp_line
			(start -2.3 2.3)
			(end 4.8 2.3)
			(stroke
				(width 0.05)
				(type solid)
			)
			(layer "B.CrtYd")
		)
		(fp_line
			(start 4.8 2.3)
			(end 5.32 1.8)
			(stroke
				(width 0.05)
				(type solid)
			)
			(layer "B.CrtYd")
		)
		(fp_line
			(start 5.32 1.8)
			(end 5.32 -1.8)
			(stroke
				(width 0.05)
				(type solid)
			)
			(layer "B.CrtYd")
		)
		(fp_line
			(start -5.33 1.1)
			(end -2.3 2.3)
			(stroke
				(width 0.05)
				(type solid)
			)
			(layer "B.CrtYd")
		)
		(fp_line
			(start -5.33 -1)
			(end -5.33 1.1)
			(stroke
				(width 0.05)
				(type solid)
			)
			(layer "B.CrtYd")
		)
		(fp_line
			(start -2.4 -2.29)
			(end -5.33 -1)
			(stroke
				(width 0.05)
				(type solid)
			)
			(layer "B.CrtYd")
		)
		(fp_line
			(start 4.8 -2.29)
			(end 5.32 -1.8)
			(stroke
				(width 0.05)
				(type solid)
			)
			(layer "B.CrtYd")
		)
		(fp_line
			(start 4.8 -2.29)
			(end -2.4 -2.29)
			(stroke
				(width 0.05)
				(type solid)
			)
			(layer "B.CrtYd")
		)
		(fp_text user "${REFERENCE}"
			(at -6.223 -6.049 90)
			(layer "B.Fab")
			(effects
				(font
					(size 0.7 0.7)
					(thickness 0.15)
				)
				(justify left bottom mirror)
			)
		)
		(fp_text user "License: Apache-2.0"
			(at -6.223 -8.449 90)
			(layer "B.Fab")
			(effects
				(font
					(size 0.7 0.7)
					(thickness 0.15)
				)
				(justify left bottom mirror)
			)
		)
		(fp_text user "Author: Antmicro"
			(at -6.223 -7.249 90)
			(layer "B.Fab")
			(effects
				(font
					(size 0.7 0.7)
					(thickness 0.15)
				)
				(justify left bottom mirror)
			)
		)
		(pad "" np_thru_hole circle
			(at -3.81 0 270)
			(size 0.9906 0.9906)
			(drill 0.9906)
			(layers "*.Cu" "*.Mask")
		)
		(pad "" np_thru_hole circle
			(at 3.809 -1.015 270)
			(size 0.9906 0.9906)
			(drill 0.9906)
			(layers "*.Cu" "*.Mask")
		)
		(pad "" np_thru_hole circle
			(at 3.809 1.016 270)
			(size 0.9906 0.9906)
			(drill 0.9906)
			(layers "*.Cu" "*.Mask")
		)
		(pad "1" connect circle
			(at -2.54 -0.634 270)
			(size 0.7874 0.7874)
			(layers "B.Cu" "B.Mask")
			(net 423 "unconnected-(J2-Pad1)")
			(pinfunction "3V3")
			(pintype "passive+no_connect")
		)
		(pad "2" connect circle
			(at -1.27 -0.634 270)
			(size 0.7874 0.7874)
			(layers "B.Cu" "B.Mask")
			(net 4 "/X710-AT2 PCIe/PCIe_JTAG.JTMS")
			(pinfunction "JTAG_TMS")
			(pintype "passive")
		)
		(pad "3" connect circle
			(at 0 -0.634 270)
			(size 0.7874 0.7874)
			(layers "B.Cu" "B.Mask")
			(net 23 "GND")
			(pinfunction "GND")
			(pintype "passive")
		)
		(pad "4" connect circle
			(at 1.269 -0.634 270)
			(size 0.7874 0.7874)
			(layers "B.Cu" "B.Mask")
			(net 16 "/X710-AT2 PCIe/PCIe_JTAG.JTCK")
			(pinfunction "JTAG_TCK")
			(pintype "passive")
		)
		(pad "5" connect circle
			(at 2.539 -0.634 270)
			(size 0.7874 0.7874)
			(layers "B.Cu" "B.Mask")
			(net 23 "GND")
			(pinfunction "GND")
			(pintype "passive")
		)
		(pad "6" connect circle
			(at 2.539 0.635 270)
			(size 0.7874 0.7874)
			(layers "B.Cu" "B.Mask")
			(net 8 "/X710-AT2 PCIe/PCIe_JTAG.JTDO")
			(pinfunction "JTAG_TDO")
			(pintype "passive")
		)
		(pad "7" connect circle
			(at 1.269 0.635 270)
			(size 0.7874 0.7874)
			(layers "B.Cu" "B.Mask")
			(net 422 "unconnected-(J2-Pad7)")
			(pinfunction "NC")
			(pintype "no_connect")
		)
		(pad "8" connect circle
			(at 0 0.635 270)
			(size 0.7874 0.7874)
			(layers "B.Cu" "B.Mask")
			(net 11 "/X710-AT2 PCIe/PCIe_JTAG.JTDI")
			(pinfunction "JTAG_TDI")
			(pintype "passive")
		)
		(pad "9" connect circle
			(at -1.27 0.635 270)
			(size 0.7874 0.7874)
			(layers "B.Cu" "B.Mask")
			(net 23 "GND")
			(pinfunction "GND")
			(pintype "passive")
		)
		(pad "10" connect circle
			(at -2.54 0.635 270)
			(size 0.7874 0.7874)
			(layers "B.Cu" "B.Mask")
			(net 15 "/X710-AT2 PCIe/PCIe_JTAG.~{JRST}")
			(pinfunction "JTAG_~{RESET}")
			(pintype "passive")
		)
	)
	(footprint "antmicro-footprints:R_0402_1005Metric"
		(layer "B.Cu")
		(at 153.831866 89.685117 90)
		(descr "Resistor SMD 0402")
		(tags "resistor SMD 0402")
		(property "Reference" "R206"
			(at -9.914883 18.568134 270)
			(layer "B.SilkS")
			(effects
				(font
					(size 0.7 0.7)
					(thickness 0.15)
				)
				(justify mirror)
			)
		)
		(property "Value" "R_4k53_0402"
			(at -1.011843 -1.772047 270)
			(layer "B.Fab")
			(effects
				(font
					(size 0.7 0.7)
					(thickness 0.15)
				)
				(justify left bottom mirror)
			)
		)
		(property "Datasheet" "https://industrial.panasonic.com/cdbs/www-data/pdf/RDM0000/AOA0000C307.pdf"
			(at 0 0 270)
			(layer "B.Fab")
			(hide yes)
			(effects
				(font
					(size 1.27 1.27)
					(thickness 0.15)
				)
				(justify mirror)
			)
		)
		(property "Description" "SMD Chip Resistor, 4.53 kohm, ± 0.1%, 62.5 mW, 0402 [1005 Metric], Automotive AEC-Q200 Thin Film"
			(at 0 0 270)
			(layer "B.Fab")
			(hide yes)
			(effects
				(font
					(size 1.27 1.27)
					(thickness 0.15)
				)
				(justify mirror)
			)
		)
		(property "MPN" "ERA-2AEB4531X"
			(at 0 0 90)
			(unlocked yes)
			(layer "B.Fab")
			(hide yes)
			(effects
				(font
					(size 1 1)
					(thickness 0.15)
				)
				(justify mirror)
			)
		)
		(property "Manufacturer" "Panasonic"
			(at 0 0 90)
			(unlocked yes)
			(layer "B.Fab")
			(hide yes)
			(effects
				(font
					(size 1 1)
					(thickness 0.15)
				)
				(justify mirror)
			)
		)
		(property "License" "Apache-2.0"
			(at 0 0 90)
			(unlocked yes)
			(layer "B.Fab")
			(hide yes)
			(effects
				(font
					(size 1 1)
					(thickness 0.15)
				)
				(justify mirror)
			)
		)
		(property "Author" "Antmicro"
			(at 0 0 90)
			(unlocked yes)
			(layer "B.Fab")
			(hide yes)
			(effects
				(font
					(size 1 1)
					(thickness 0.15)
				)
				(justify mirror)
			)
		)
		(property "Val" "4k53"
			(at 0 0 90)
			(unlocked yes)
			(layer "B.Fab")
			(hide yes)
			(effects
				(font
					(size 1 1)
					(thickness 0.15)
				)
				(justify mirror)
			)
		)
		(property "Tolerance" "0.1%"
			(at 0 0 90)
			(unlocked yes)
			(layer "B.Fab")
			(hide yes)
			(effects
				(font
					(size 1 1)
					(thickness 0.15)
				)
				(justify mirror)
			)
		)
		(sheetname "/X710-AT2 10GbE/")
		(sheetfile "x710-at2-10gbe.kicad_sch")
		(attr smd)
		(fp_rect
			(start -0.925 0.47)
			(end 0.925 -0.47)
			(stroke
				(width 0.05)
				(type default)
			)
			(fill no)
			(layer "B.CrtYd")
		)
		(fp_rect
			(start -0.5 0.25)
			(end 0.5 -0.25)
			(stroke
				(width 0.15)
				(type solid)
			)
			(fill no)
			(layer "B.Fab")
		)
		(fp_text user "License: Apache-2.0"
			(at -0.95 -5.169 270)
			(layer "B.Fab")
			(effects
				(font
					(size 0.7 0.7)
					(thickness 0.15)
				)
				(justify left bottom mirror)
			)
		)
		(fp_text user "${REFERENCE}"
			(at -0.95 -3.168 270)
			(layer "B.Fab")
			(effects
				(font
					(size 0.7 0.7)
					(thickness 0.15)
				)
				(justify left bottom mirror)
			)
		)
		(fp_text user "Author: Antmicro"
			(at -0.95 -4.169 270)
			(layer "B.Fab")
			(effects
				(font
					(size 0.7 0.7)
					(thickness 0.15)
				)
				(justify left bottom mirror)
			)
		)
		(pad "1" smd roundrect
			(at -0.48 0 90)
			(size 0.59 0.64)
			(layers "B.Cu" "B.Mask" "B.Paste")
			(roundrect_rratio 0.25)
			(net 23 "GND")
			(pintype "passive")
		)
		(pad "2" smd roundrect
			(at 0.48 0 90)
			(size 0.59 0.64)
			(layers "B.Cu" "B.Mask" "B.Paste")
			(roundrect_rratio 0.25)
			(net 62 "/X710-AT2 10GbE/RESCAL_RES_P")
			(pintype "passive")
		)
	)
	(footprint "antmicro-footprints:R_0402_1005Metric"
		(layer "B.Cu")
		(at 135.75 140.9 -90)
		(descr "Resistor SMD 0402")
		(tags "resistor SMD 0402")
		(property "Reference" "R31"
			(at -9.557574 -19.525001 90)
			(layer "B.SilkS")
			(effects
				(font
					(size 0.7 0.7)
					(thickness 0.15)
				)
				(justify mirror)
			)
		)
		(property "Value" "R_10k_0402"
			(at -1.011843 -1.772047 90)
			(layer "B.Fab")
			(effects
				(font
					(size 0.7 0.7)
					(thickness 0.15)
				)
				(justify left bottom mirror)
			)
		)
		(property "Datasheet" "https://www.bourns.com/docs/product-datasheets/cr.pdf"
			(at 0 0 90)
			(layer "B.Fab")
			(hide yes)
			(effects
				(font
					(size 1.27 1.27)
					(thickness 0.15)
				)
				(justify mirror)
			)
		)
		(property "Description" "SMD Chip Resistor, 10 kohm, ± 1%, 62.5 mW, 0402 [1005 Metric], Thick Film, General Purpose"
			(at 0 0 90)
			(layer "B.Fab")
			(hide yes)
			(effects
				(font
					(size 1.27 1.27)
					(thickness 0.15)
				)
				(justify mirror)
			)
		)
		(property "MPN" "CR0402-FX-1002GLF"
			(at 0 0 270)
			(unlocked yes)
			(layer "B.Fab")
			(hide yes)
			(effects
				(font
					(size 1 1)
					(thickness 0.15)
				)
				(justify mirror)
			)
		)
		(property "Manufacturer" "Bourns"
			(at 0 0 270)
			(unlocked yes)
			(layer "B.Fab")
			(hide yes)
			(effects
				(font
					(size 1 1)
					(thickness 0.15)
				)
				(justify mirror)
			)
		)
		(property "License" "Apache-2.0"
			(at 0 0 270)
			(unlocked yes)
			(layer "B.Fab")
			(hide yes)
			(effects
				(font
					(size 1 1)
					(thickness 0.15)
				)
				(justify mirror)
			)
		)
		(property "Val" "10k"
			(at 0 0 270)
			(unlocked yes)
			(layer "B.Fab")
			(hide yes)
			(effects
				(font
					(size 1 1)
					(thickness 0.15)
				)
				(justify mirror)
			)
		)
		(property "Tolerance" "1%"
			(at 0 0 270)
			(unlocked yes)
			(layer "B.Fab")
			(hide yes)
			(effects
				(font
					(size 1 1)
					(thickness 0.15)
				)
				(justify mirror)
			)
		)
		(property "Author" "Antmicro"
			(at 0 0 270)
			(unlocked yes)
			(layer "B.Fab")
			(hide yes)
			(effects
				(font
					(size 1 1)
					(thickness 0.15)
				)
				(justify mirror)
			)
		)
		(sheetname "/PD and TB DC-DC/")
		(sheetfile "PD_and_TB_DC_DC.kicad_sch")
		(attr smd)
		(fp_rect
			(start -0.925 0.47)
			(end 0.925 -0.47)
			(stroke
				(width 0.05)
				(type default)
			)
			(fill no)
			(layer "B.CrtYd")
		)
		(fp_rect
			(start -0.5 0.25)
			(end 0.5 -0.25)
			(stroke
				(width 0.15)
				(type solid)
			)
			(fill no)
			(layer "B.Fab")
		)
		(fp_text user "Author: Antmicro"
			(at -0.95 -4.169 90)
			(layer "B.Fab")
			(effects
				(font
					(size 0.7 0.7)
					(thickness 0.15)
				)
				(justify left bottom mirror)
			)
		)
		(fp_text user "License: Apache-2.0"
			(at -0.95 -5.169 90)
			(layer "B.Fab")
			(effects
				(font
					(size 0.7 0.7)
					(thickness 0.15)
				)
				(justify left bottom mirror)
			)
		)
		(fp_text user "${REFERENCE}"
			(at -0.95 -3.168 90)
			(layer "B.Fab")
			(effects
				(font
					(size 0.7 0.7)
					(thickness 0.15)
				)
				(justify left bottom mirror)
			)
		)
		(pad "1" smd roundrect
			(at -0.48 0 270)
			(size 0.59 0.64)
			(layers "B.Cu" "B.Mask" "B.Paste")
			(roundrect_rratio 0.25)
			(net 377 "/PD and TB DC-DC/RESET_N")
			(pintype "passive")
		)
		(pad "2" smd roundrect
			(at 0.48 0 270)
			(size 0.59 0.64)
			(layers "B.Cu" "B.Mask" "B.Paste")
			(roundrect_rratio 0.25)
			(net 304 "/PD and TB DC-DC/TPS_3V3")
			(pintype "passive")
		)
	)
	(footprint "antmicro-footprints:R_0402_1005Metric"
		(layer "B.Cu")
		(at 142.500001 117.15 180)
		(descr "Resistor SMD 0402")
		(tags "resistor SMD 0402")
		(property "Reference" "R64"
			(at -19.75 7.450001 0)
			(layer "B.SilkS")
			(effects
				(font
					(size 0.7 0.7)
					(thickness 0.15)
				)
				(justify mirror)
			)
		)
		(property "Value" "R_10k_0402"
			(at -1.011843 -1.772047 0)
			(layer "B.Fab")
			(effects
				(font
					(size 0.7 0.7)
					(thickness 0.15)
				)
				(justify left bottom mirror)
			)
		)
		(property "Datasheet" "https://www.bourns.com/docs/product-datasheets/cr.pdf"
			(at 0 0 0)
			(layer "B.Fab")
			(hide yes)
			(effects
				(font
					(size 1.27 1.27)
					(thickness 0.15)
				)
				(justify mirror)
			)
		)
		(property "Description" "SMD Chip Resistor, 10 kohm, ± 1%, 62.5 mW, 0402 [1005 Metric], Thick Film, General Purpose"
			(at 0 0 0)
			(layer "B.Fab")
			(hide yes)
			(effects
				(font
					(size 1.27 1.27)
					(thickness 0.15)
				)
				(justify mirror)
			)
		)
		(property "MPN" "CR0402-FX-1002GLF"
			(at 0 0 180)
			(unlocked yes)
			(layer "B.Fab")
			(hide yes)
			(effects
				(font
					(size 1 1)
					(thickness 0.15)
				)
				(justify mirror)
			)
		)
		(property "Manufacturer" "Bourns"
			(at 0 0 180)
			(unlocked yes)
			(layer "B.Fab")
			(hide yes)
			(effects
				(font
					(size 1 1)
					(thickness 0.15)
				)
				(justify mirror)
			)
		)
		(property "License" "Apache-2.0"
			(at 0 0 180)
			(unlocked yes)
			(layer "B.Fab")
			(hide yes)
			(effects
				(font
					(size 1 1)
					(thickness 0.15)
				)
				(justify mirror)
			)
		)
		(property "Val" "10k"
			(at 0 0 180)
			(unlocked yes)
			(layer "B.Fab")
			(hide yes)
			(effects
				(font
					(size 1 1)
					(thickness 0.15)
				)
				(justify mirror)
			)
		)
		(property "Tolerance" "1%"
			(at 0 0 180)
			(unlocked yes)
			(layer "B.Fab")
			(hide yes)
			(effects
				(font
					(size 1 1)
					(thickness 0.15)
				)
				(justify mirror)
			)
		)
		(property "Author" "Antmicro"
			(at 0 0 180)
			(unlocked yes)
			(layer "B.Fab")
			(hide yes)
			(effects
				(font
					(size 1 1)
					(thickness 0.15)
				)
				(justify mirror)
			)
		)
		(sheetname "/TB Controller/")
		(sheetfile "tb.kicad_sch")
		(attr smd)
		(fp_rect
			(start -0.925 0.47)
			(end 0.925 -0.47)
			(stroke
				(width 0.05)
				(type default)
			)
			(fill no)
			(layer "B.CrtYd")
		)
		(fp_rect
			(start -0.5 0.25)
			(end 0.5 -0.25)
			(stroke
				(width 0.15)
				(type solid)
			)
			(fill no)
			(layer "B.Fab")
		)
		(fp_text user "License: Apache-2.0"
			(at -0.95 -5.169 0)
			(layer "B.Fab")
			(effects
				(font
					(size 0.7 0.7)
					(thickness 0.15)
				)
				(justify left bottom mirror)
			)
		)
		(fp_text user "${REFERENCE}"
			(at -0.95 -3.168 0)
			(layer "B.Fab")
			(effects
				(font
					(size 0.7 0.7)
					(thickness 0.15)
				)
				(justify left bottom mirror)
			)
		)
		(fp_text user "Author: Antmicro"
			(at -0.95 -4.169 0)
			(layer "B.Fab")
			(effects
				(font
					(size 0.7 0.7)
					(thickness 0.15)
				)
				(justify left bottom mirror)
			)
		)
		(pad "1" smd roundrect
			(at -0.48 0 180)
			(size 0.59 0.64)
			(layers "B.Cu" "B.Mask" "B.Paste")
			(roundrect_rratio 0.25)
			(net 57 "+3V3_TB")
			(pintype "passive")
		)
		(pad "2" smd roundrect
			(at 0.48 0 180)
			(size 0.59 0.64)
			(layers "B.Cu" "B.Mask" "B.Paste")
			(roundrect_rratio 0.25)
			(net 226 "Net-(U4D-TCK)")
			(pintype "passive")
		)
	)
)
